(kicad_pcb
	(version 20260206)
	(generator "pcbnew")
	(generator_version "10.0")
	(general
		(thickness 1.6)
		(legacy_teardrops no)
	)
	(paper "A4")
	(title_block
		(title "01162023_DA0F0TEBIF0_F0T_Expander_BD_F_brd_V02_OCP.brd")
		(comment 1 "Grand Teton / footprints 2240-2245 of 9728")
	)
	(layers
		(0 "F.Cu" signal "TOP")
		(4 "In1.Cu" signal "GND")
		(6 "In2.Cu" signal "VCC")
		(8 "In3.Cu" signal "VCC1")
		(10 "In4.Cu" signal "GND1")
		(12 "In5.Cu" signal "IN1")
		(14 "In6.Cu" signal "GND2")
		(16 "In7.Cu" signal "IN2")
		(18 "In8.Cu" signal "GND3")
		(20 "In9.Cu" signal "IN3")
		(22 "In10.Cu" signal "GND4")
		(24 "In11.Cu" signal "IN4")
		(26 "In12.Cu" signal "GND5")
		(28 "In13.Cu" signal "IN5")
		(30 "In14.Cu" signal "GND6")
		(32 "In15.Cu" signal "IN6")
		(34 "In16.Cu" signal "GND7")
		(2 "B.Cu" signal "BOTTOM")
		(9 "F.Adhes" user "F.Adhesive")
		(11 "B.Adhes" user "B.Adhesive")
		(13 "F.Paste" user "Package Geometry/Pastemask Top")
		(15 "B.Paste" user "Package Geometry/Pastemask Bottom")
		(5 "F.SilkS" user "Ref Des/Silkscreen Top")
		(7 "B.SilkS" user "Ref Des/Silkscreen Bottom")
		(1 "F.Mask" user "Board Geometry/Soldermask Top")
		(3 "B.Mask" user "Board Geometry/Soldermask Bottom")
		(17 "Dwgs.User" user "User.Drawings")
		(19 "Cmts.User" user "User.Comments")
		(21 "Eco1.User" user "User.Eco1")
		(23 "Eco2.User" user "User.Eco2")
		(25 "Edge.Cuts" user "Board Geometry/Outline")
		(27 "Margin" user)
		(31 "F.CrtYd" user "Package Geometry/Place Bound Top")
		(29 "B.CrtYd" user "Package Geometry/Place Bound Bottom")
		(35 "F.Fab" user "Ref Des/Assembly Top")
		(33 "B.Fab" user "Ref Des/Assembly Bottom")
	)
	(footprint ""
		(layer "F.Cu")
		(at 380.711456 -296.445432 -90)
		(property "Reference" "R4588"
			(at 0 0 270)
			(layer "F.SilkS")
			(hide yes)
			(effects
				(font
					(size 1.27 1.27)
				)
			)
		)
		(property "Value" ""
			(at 0 0 270)
			(layer "F.Fab")
			(effects
				(font
					(size 1.27 1.27)
				)
			)
		)
		(duplicate_pad_numbers_are_jumpers no)
		(fp_line
			(start -0.7874 0.4064)
			(end -0.7874 -0.4064)
			(stroke
				(width 0.1524)
				(type default)
			)
			(layer "F.SilkS")
		)
		(fp_line
			(start 0.7874 0.4064)
			(end -0.7874 0.4064)
			(stroke
				(width 0.1524)
				(type default)
			)
			(layer "F.SilkS")
		)
		(fp_line
			(start -0.7874 -0.4064)
			(end 0.7874 -0.4064)
			(stroke
				(width 0.1524)
				(type default)
			)
			(layer "F.SilkS")
		)
		(fp_line
			(start 0.7874 -0.4064)
			(end 0.7874 0.4064)
			(stroke
				(width 0.1524)
				(type default)
			)
			(layer "F.SilkS")
		)
		(fp_line
			(start -0.67945 0.3048)
			(end -0.67945 -0.305054)
			(stroke
				(width 0.1)
				(type default)
			)
			(layer "F.Fab")
		)
		(fp_line
			(start -0.12065 0.3048)
			(end -0.67945 0.3048)
			(stroke
				(width 0.1)
				(type default)
			)
			(layer "F.Fab")
		)
		(fp_line
			(start 0.120396 0.3048)
			(end 0.120396 0.2794)
			(stroke
				(width 0.1)
				(type default)
			)
			(layer "F.Fab")
		)
		(fp_line
			(start 0.67945 0.3048)
			(end 0.120396 0.3048)
			(stroke
				(width 0.1)
				(type default)
			)
			(layer "F.Fab")
		)
		(fp_line
			(start -0.12065 0.2794)
			(end -0.12065 0.3048)
			(stroke
				(width 0.1)
				(type default)
			)
			(layer "F.Fab")
		)
		(fp_line
			(start 0.120396 0.2794)
			(end -0.12065 0.2794)
			(stroke
				(width 0.1)
				(type default)
			)
			(layer "F.Fab")
		)
		(fp_line
			(start -0.12065 -0.2794)
			(end 0.12065 -0.2794)
			(stroke
				(width 0.1)
				(type default)
			)
			(layer "F.Fab")
		)
		(fp_line
			(start 0.12065 -0.2794)
			(end 0.12065 -0.3048)
			(stroke
				(width 0.1)
				(type default)
			)
			(layer "F.Fab")
		)
		(fp_line
			(start 0.12065 -0.3048)
			(end 0.67945 -0.3048)
			(stroke
				(width 0.1)
				(type default)
			)
			(layer "F.Fab")
		)
		(fp_line
			(start 0.67945 -0.3048)
			(end 0.67945 0.3048)
			(stroke
				(width 0.1)
				(type default)
			)
			(layer "F.Fab")
		)
		(fp_line
			(start -0.67945 -0.305054)
			(end -0.12065 -0.305054)
			(stroke
				(width 0.1)
				(type default)
			)
			(layer "F.Fab")
		)
		(fp_line
			(start -0.12065 -0.305054)
			(end -0.12065 -0.2794)
			(stroke
				(width 0.1)
				(type default)
			)
			(layer "F.Fab")
		)
		(pad "1" smd circle
			(at -0.40005 0 270)
			(size 0 0)
			(layers "F.Cu" "F.Mask" "F.Paste")
			(net "PCEPLL0_VDDA18_PEX3")
		)
		(pad "2" smd circle
			(at 0.40005 0 270)
			(size 0 0)
			(layers "F.Cu" "F.Mask" "F.Paste")
			(net "PCEPLL0_VDDA18_PEX3_R")
		)
	)
	(footprint ""
		(layer "F.Cu")
		(at 76.477114 -49.856644)
		(property "Reference" "R5894"
			(at 0 0 0)
			(layer "F.SilkS")
			(hide yes)
			(effects
				(font
					(size 1.27 1.27)
				)
			)
		)
		(property "Value" ""
			(at 0 0 0)
			(layer "F.Fab")
			(effects
				(font
					(size 1.27 1.27)
				)
			)
		)
		(duplicate_pad_numbers_are_jumpers no)
		(fp_line
			(start -0.7874 -0.4064)
			(end 0.7874 -0.4064)
			(stroke
				(width 0.1524)
				(type default)
			)
			(layer "F.SilkS")
		)
		(fp_line
			(start -0.7874 0.4064)
			(end -0.7874 -0.4064)
			(stroke
				(width 0.1524)
				(type default)
			)
			(layer "F.SilkS")
		)
		(fp_line
			(start 0.7874 -0.4064)
			(end 0.7874 0.4064)
			(stroke
				(width 0.1524)
				(type default)
			)
			(layer "F.SilkS")
		)
		(fp_line
			(start 0.7874 0.4064)
			(end -0.7874 0.4064)
			(stroke
				(width 0.1524)
				(type default)
			)
			(layer "F.SilkS")
		)
		(fp_line
			(start -0.67945 -0.305054)
			(end -0.12065 -0.305054)
			(stroke
				(width 0.1)
				(type default)
			)
			(layer "F.Fab")
		)
		(fp_line
			(start -0.67945 0.3048)
			(end -0.67945 -0.305054)
			(stroke
				(width 0.1)
				(type default)
			)
			(layer "F.Fab")
		)
		(fp_line
			(start -0.12065 -0.305054)
			(end -0.12065 -0.2794)
			(stroke
				(width 0.1)
				(type default)
			)
			(layer "F.Fab")
		)
		(fp_line
			(start -0.12065 -0.2794)
			(end 0.12065 -0.2794)
			(stroke
				(width 0.1)
				(type default)
			)
			(layer "F.Fab")
		)
		(fp_line
			(start -0.12065 0.2794)
			(end -0.12065 0.3048)
			(stroke
				(width 0.1)
				(type default)
			)
			(layer "F.Fab")
		)
		(fp_line
			(start -0.12065 0.3048)
			(end -0.67945 0.3048)
			(stroke
				(width 0.1)
				(type default)
			)
			(layer "F.Fab")
		)
		(fp_line
			(start 0.120396 0.2794)
			(end -0.12065 0.2794)
			(stroke
				(width 0.1)
				(type default)
			)
			(layer "F.Fab")
		)
		(fp_line
			(start 0.120396 0.3048)
			(end 0.120396 0.2794)
			(stroke
				(width 0.1)
				(type default)
			)
			(layer "F.Fab")
		)
		(fp_line
			(start 0.12065 -0.3048)
			(end 0.67945 -0.3048)
			(stroke
				(width 0.1)
				(type default)
			)
			(layer "F.Fab")
		)
		(fp_line
			(start 0.12065 -0.2794)
			(end 0.12065 -0.3048)
			(stroke
				(width 0.1)
				(type default)
			)
			(layer "F.Fab")
		)
		(fp_line
			(start 0.67945 -0.3048)
			(end 0.67945 0.3048)
			(stroke
				(width 0.1)
				(type default)
			)
			(layer "F.Fab")
		)
		(fp_line
			(start 0.67945 0.3048)
			(end 0.120396 0.3048)
			(stroke
				(width 0.1)
				(type default)
			)
			(layer "F.Fab")
		)
		(pad "1" smd circle
			(at -0.40005 0)
			(size 0 0)
			(layers "F.Cu" "F.Mask" "F.Paste")
			(net "SSD2_ADC_A0")
		)
		(pad "2" smd circle
			(at 0.40005 0)
			(size 0 0)
			(layers "F.Cu" "F.Mask" "F.Paste")
			(net "SMB_SSD2_ADC_SDA")
		)
	)
	(footprint ""
		(layer "F.Cu")
		(at 37.1856 -115.2652 90)
		(property "Reference" "R44"
			(at 0 0 90)
			(layer "F.SilkS")
			(hide yes)
			(effects
				(font
					(size 1.27 1.27)
				)
			)
		)
		(property "Value" ""
			(at 0 0 90)
			(layer "F.Fab")
			(effects
				(font
					(size 1.27 1.27)
				)
			)
		)
		(duplicate_pad_numbers_are_jumpers no)
		(fp_line
			(start 0.7874 -0.4064)
			(end 0.7874 0.4064)
			(stroke
				(width 0.1524)
				(type default)
			)
			(layer "F.SilkS")
		)
		(fp_line
			(start -0.7874 -0.4064)
			(end 0.7874 -0.4064)
			(stroke
				(width 0.1524)
				(type default)
			)
			(layer "F.SilkS")
		)
		(fp_line
			(start 0.7874 0.4064)
			(end -0.7874 0.4064)
			(stroke
				(width 0.1524)
				(type default)
			)
			(layer "F.SilkS")
		)
		(fp_line
			(start -0.7874 0.4064)
			(end -0.7874 -0.4064)
			(stroke
				(width 0.1524)
				(type default)
			)
			(layer "F.SilkS")
		)
		(fp_line
			(start -0.12065 -0.305054)
			(end -0.12065 -0.2794)
			(stroke
				(width 0.1)
				(type default)
			)
			(layer "F.Fab")
		)
		(fp_line
			(start -0.67945 -0.305054)
			(end -0.12065 -0.305054)
			(stroke
				(width 0.1)
				(type default)
			)
			(layer "F.Fab")
		)
		(fp_line
			(start 0.67945 -0.3048)
			(end 0.67945 0.3048)
			(stroke
				(width 0.1)
				(type default)
			)
			(layer "F.Fab")
		)
		(fp_line
			(start 0.12065 -0.3048)
			(end 0.67945 -0.3048)
			(stroke
				(width 0.1)
				(type default)
			)
			(layer "F.Fab")
		)
		(fp_line
			(start 0.12065 -0.2794)
			(end 0.12065 -0.3048)
			(stroke
				(width 0.1)
				(type default)
			)
			(layer "F.Fab")
		)
		(fp_line
			(start -0.12065 -0.2794)
			(end 0.12065 -0.2794)
			(stroke
				(width 0.1)
				(type default)
			)
			(layer "F.Fab")
		)
		(fp_line
			(start 0.120396 0.2794)
			(end -0.12065 0.2794)
			(stroke
				(width 0.1)
				(type default)
			)
			(layer "F.Fab")
		)
		(fp_line
			(start -0.12065 0.2794)
			(end -0.12065 0.3048)
			(stroke
				(width 0.1)
				(type default)
			)
			(layer "F.Fab")
		)
		(fp_line
			(start 0.67945 0.3048)
			(end 0.120396 0.3048)
			(stroke
				(width 0.1)
				(type default)
			)
			(layer "F.Fab")
		)
		(fp_line
			(start 0.120396 0.3048)
			(end 0.120396 0.2794)
			(stroke
				(width 0.1)
				(type default)
			)
			(layer "F.Fab")
		)
		(fp_line
			(start -0.12065 0.3048)
			(end -0.67945 0.3048)
			(stroke
				(width 0.1)
				(type default)
			)
			(layer "F.Fab")
		)
		(fp_line
			(start -0.67945 0.3048)
			(end -0.67945 -0.305054)
			(stroke
				(width 0.1)
				(type default)
			)
			(layer "F.Fab")
		)
		(pad "1" smd circle
			(at -0.40005 0 90)
			(size 0 0)
			(layers "F.Cu" "F.Mask" "F.Paste")
			(net "P3V3_AUX")
		)
		(pad "2" smd circle
			(at 0.40005 0 90)
			(size 0 0)
			(layers "F.Cu" "F.Mask" "F.Paste")
			(net "HP_NIC0_EN")
		)
	)
	(footprint ""
		(layer "F.Cu")
		(at 63.002668 -388.33679 -90)
		(property "Reference" "C4048"
			(at 0 0 270)
			(layer "F.SilkS")
			(hide yes)
			(effects
				(font
					(size 1.27 1.27)
				)
			)
		)
		(property "Value" ""
			(at 0 0 270)
			(layer "F.Fab")
			(effects
				(font
					(size 1.27 1.27)
				)
			)
		)
		(duplicate_pad_numbers_are_jumpers no)
		(fp_line
			(start -0.7874 0.4064)
			(end -0.7874 -0.4064)
			(stroke
				(width 0.1524)
				(type default)
			)
			(layer "F.SilkS")
		)
		(fp_line
			(start 0.7874 0.4064)
			(end -0.7874 0.4064)
			(stroke
				(width 0.1524)
				(type default)
			)
			(layer "F.SilkS")
		)
		(fp_line
			(start -0.7874 -0.4064)
			(end 0.7874 -0.4064)
			(stroke
				(width 0.1524)
				(type default)
			)
			(layer "F.SilkS")
		)
		(fp_line
			(start 0.7874 -0.4064)
			(end 0.7874 0.4064)
			(stroke
				(width 0.1524)
				(type default)
			)
			(layer "F.SilkS")
		)
		(fp_line
			(start -0.67945 0.3048)
			(end -0.67945 -0.305054)
			(stroke
				(width 0.1)
				(type default)
			)
			(layer "F.Fab")
		)
		(fp_line
			(start -0.12065 0.3048)
			(end -0.67945 0.3048)
			(stroke
				(width 0.1)
				(type default)
			)
			(layer "F.Fab")
		)
		(fp_line
			(start 0.120396 0.3048)
			(end 0.120396 0.2794)
			(stroke
				(width 0.1)
				(type default)
			)
			(layer "F.Fab")
		)
		(fp_line
			(start 0.67945 0.3048)
			(end 0.120396 0.3048)
			(stroke
				(width 0.1)
				(type default)
			)
			(layer "F.Fab")
		)
		(fp_line
			(start -0.12065 0.2794)
			(end -0.12065 0.3048)
			(stroke
				(width 0.1)
				(type default)
			)
			(layer "F.Fab")
		)
		(fp_line
			(start 0.120396 0.2794)
			(end -0.12065 0.2794)
			(stroke
				(width 0.1)
				(type default)
			)
			(layer "F.Fab")
		)
		(fp_line
			(start -0.12065 -0.2794)
			(end 0.12065 -0.2794)
			(stroke
				(width 0.1)
				(type default)
			)
			(layer "F.Fab")
		)
		(fp_line
			(start 0.12065 -0.2794)
			(end 0.12065 -0.3048)
			(stroke
				(width 0.1)
				(type default)
			)
			(layer "F.Fab")
		)
		(fp_line
			(start 0.12065 -0.3048)
			(end 0.67945 -0.3048)
			(stroke
				(width 0.1)
				(type default)
			)
			(layer "F.Fab")
		)
		(fp_line
			(start 0.67945 -0.3048)
			(end 0.67945 0.3048)
			(stroke
				(width 0.1)
				(type default)
			)
			(layer "F.Fab")
		)
		(fp_line
			(start -0.67945 -0.305054)
			(end -0.12065 -0.305054)
			(stroke
				(width 0.1)
				(type default)
			)
			(layer "F.Fab")
		)
		(fp_line
			(start -0.12065 -0.305054)
			(end -0.12065 -0.2794)
			(stroke
				(width 0.1)
				(type default)
			)
			(layer "F.Fab")
		)
		(pad "1" smd circle
			(at -0.40005 0 270)
			(size 0 0)
			(layers "F.Cu" "F.Mask" "F.Paste")
			(net "GND")
		)
		(pad "2" smd circle
			(at 0.40005 0 270)
			(size 0 0)
			(layers "F.Cu" "F.Mask" "F.Paste")
			(net "GPU_PEX_STRAP1")
		)
	)
	(footprint ""
		(layer "F.Cu")
		(at 333.540608 -236.871256 -90)
		(property "Reference" "R1789"
			(at 0 0 270)
			(layer "F.SilkS")
			(hide yes)
			(effects
				(font
					(size 1.27 1.27)
				)
			)
		)
		(property "Value" ""
			(at 0 0 270)
			(layer "F.Fab")
			(effects
				(font
					(size 1.27 1.27)
				)
			)
		)
		(duplicate_pad_numbers_are_jumpers no)
		(fp_line
			(start -0.7874 0.4064)
			(end -0.7874 -0.4064)
			(stroke
				(width 0.1524)
				(type default)
			)
			(layer "F.SilkS")
		)
		(fp_line
			(start 0.7874 0.4064)
			(end -0.7874 0.4064)
			(stroke
				(width 0.1524)
				(type default)
			)
			(layer "F.SilkS")
		)
		(fp_line
			(start -0.7874 -0.4064)
			(end 0.7874 -0.4064)
			(stroke
				(width 0.1524)
				(type default)
			)
			(layer "F.SilkS")
		)
		(fp_line
			(start 0.7874 -0.4064)
			(end 0.7874 0.4064)
			(stroke
				(width 0.1524)
				(type default)
			)
			(layer "F.SilkS")
		)
		(fp_line
			(start -0.67945 0.3048)
			(end -0.67945 -0.305054)
			(stroke
				(width 0.1)
				(type default)
			)
			(layer "F.Fab")
		)
		(fp_line
			(start -0.12065 0.3048)
			(end -0.67945 0.3048)
			(stroke
				(width 0.1)
				(type default)
			)
			(layer "F.Fab")
		)
		(fp_line
			(start 0.120396 0.3048)
			(end 0.120396 0.2794)
			(stroke
				(width 0.1)
				(type default)
			)
			(layer "F.Fab")
		)
		(fp_line
			(start 0.67945 0.3048)
			(end 0.120396 0.3048)
			(stroke
				(width 0.1)
				(type default)
			)
			(layer "F.Fab")
		)
		(fp_line
			(start -0.12065 0.2794)
			(end -0.12065 0.3048)
			(stroke
				(width 0.1)
				(type default)
			)
			(layer "F.Fab")
		)
		(fp_line
			(start 0.120396 0.2794)
			(end -0.12065 0.2794)
			(stroke
				(width 0.1)
				(type default)
			)
			(layer "F.Fab")
		)
		(fp_line
			(start -0.12065 -0.2794)
			(end 0.12065 -0.2794)
			(stroke
				(width 0.1)
				(type default)
			)
			(layer "F.Fab")
		)
		(fp_line
			(start 0.12065 -0.2794)
			(end 0.12065 -0.3048)
			(stroke
				(width 0.1)
				(type default)
			)
			(layer "F.Fab")
		)
		(fp_line
			(start 0.12065 -0.3048)
			(end 0.67945 -0.3048)
			(stroke
				(width 0.1)
				(type default)
			)
			(layer "F.Fab")
		)
		(fp_line
			(start 0.67945 -0.3048)
			(end 0.67945 0.3048)
			(stroke
				(width 0.1)
				(type default)
			)
			(layer "F.Fab")
		)
		(fp_line
			(start -0.67945 -0.305054)
			(end -0.12065 -0.305054)
			(stroke
				(width 0.1)
				(type default)
			)
			(layer "F.Fab")
		)
		(fp_line
			(start -0.12065 -0.305054)
			(end -0.12065 -0.2794)
			(stroke
				(width 0.1)
				(type default)
			)
			(layer "F.Fab")
		)
		(pad "1" smd circle
			(at -0.40005 0 270)
			(size 0 0)
			(layers "F.Cu" "F.Mask" "F.Paste")
			(net "RST_MB_PERST_1_ISO_N")
		)
		(pad "2" smd circle
			(at 0.40005 0 270)
			(size 0 0)
			(layers "F.Cu" "F.Mask" "F.Paste")
			(net "RST_MB_PERST_1_ISO_R_N")
		)
	)
	(footprint ""
		(layer "F.Cu")
		(at 420.972996 -22.867366 90)
		(property "Reference" "C3970"
			(at 0 0 90)
			(layer "F.SilkS")
			(hide yes)
			(effects
				(font
					(size 1.27 1.27)
				)
			)
		)
		(property "Value" ""
			(at 0 0 90)
			(layer "F.Fab")
			(effects
				(font
					(size 1.27 1.27)
				)
			)
		)
		(duplicate_pad_numbers_are_jumpers no)
		(fp_line
			(start 0.7874 -0.4064)
			(end 0.7874 0.4064)
			(stroke
				(width 0.1524)
				(type default)
			)
			(layer "F.SilkS")
		)
		(fp_line
			(start -0.7874 -0.4064)
			(end 0.7874 -0.4064)
			(stroke
				(width 0.1524)
				(type default)
			)
			(layer "F.SilkS")
		)
		(fp_line
			(start 0.7874 0.4064)
			(end -0.7874 0.4064)
			(stroke
				(width 0.1524)
				(type default)
			)
			(layer "F.SilkS")
		)
		(fp_line
			(start -0.7874 0.4064)
			(end -0.7874 -0.4064)
			(stroke
				(width 0.1524)
				(type default)
			)
			(layer "F.SilkS")
		)
		(fp_line
			(start -0.12065 -0.305054)
			(end -0.12065 -0.2794)
			(stroke
				(width 0.1)
				(type default)
			)
			(layer "F.Fab")
		)
		(fp_line
			(start -0.67945 -0.305054)
			(end -0.12065 -0.305054)
			(stroke
				(width 0.1)
				(type default)
			)
			(layer "F.Fab")
		)
		(fp_line
			(start 0.67945 -0.3048)
			(end 0.67945 0.3048)
			(stroke
				(width 0.1)
				(type default)
			)
			(layer "F.Fab")
		)
		(fp_line
			(start 0.12065 -0.3048)
			(end 0.67945 -0.3048)
			(stroke
				(width 0.1)
				(type default)
			)
			(layer "F.Fab")
		)
		(fp_line
			(start 0.12065 -0.2794)
			(end 0.12065 -0.3048)
			(stroke
				(width 0.1)
				(type default)
			)
			(layer "F.Fab")
		)
		(fp_line
			(start -0.12065 -0.2794)
			(end 0.12065 -0.2794)
			(stroke
				(width 0.1)
				(type default)
			)
			(layer "F.Fab")
		)
		(fp_line
			(start 0.120396 0.2794)
			(end -0.12065 0.2794)
			(stroke
				(width 0.1)
				(type default)
			)
			(layer "F.Fab")
		)
		(fp_line
			(start -0.12065 0.2794)
			(end -0.12065 0.3048)
			(stroke
				(width 0.1)
				(type default)
			)
			(layer "F.Fab")
		)
		(fp_line
			(start 0.67945 0.3048)
			(end 0.120396 0.3048)
			(stroke
				(width 0.1)
				(type default)
			)
			(layer "F.Fab")
		)
		(fp_line
			(start 0.120396 0.3048)
			(end 0.120396 0.2794)
			(stroke
				(width 0.1)
				(type default)
			)
			(layer "F.Fab")
		)
		(fp_line
			(start -0.12065 0.3048)
			(end -0.67945 0.3048)
			(stroke
				(width 0.1)
				(type default)
			)
			(layer "F.Fab")
		)
		(fp_line
			(start -0.67945 0.3048)
			(end -0.67945 -0.305054)
			(stroke
				(width 0.1)
				(type default)
			)
			(layer "F.Fab")
		)
		(pad "1" smd circle
			(at -0.40005 0 90)
			(size 0 0)
			(layers "F.Cu" "F.Mask" "F.Paste")
			(net "P12V_SSD14")
		)
		(pad "2" smd circle
			(at 0.40005 0 90)
			(size 0 0)
			(layers "F.Cu" "F.Mask" "F.Paste")
			(net "GND")
		)
	)
)
